# S9S_MB_2U (Grand Teton) — schematic netlist excerpt (pin names and nets, part order shuffled) for the footprints in the layout excerpt that follows; sources: Cadence DE-HDL packaged netlist, KiCad conversion of 03242023_DA0F0TMBIJ0_F0T_Motherboard_J_brd_V01_OCP.brd

PC2342  Q_CAP  22UF 16V 20% X6S  pkg C0805  page 259 : A = SW_P3V3_AUX_FLT ; B = GND
PC1235  Q_CAP  0.22UF 25V 10% X7R  pkg C0402  page 263 : A = SW_P1V8_PCH_AUX_BST ; B = SW_P1V8_PCH_AUX_SW
C640  Q_CAP  0.1UF 25V 10% X7R  pkg 0402  page 154 : A = P3V3_AUX ; B = GND

(kicad_pcb
	(version 20260206)
	(generator "pcbnew")
	(generator_version "10.0")
	(general
		(thickness 1.6)
		(legacy_teardrops no)
	)
	(paper "A4")
	(title_block
		(title "03242023_DA0F0TMBIJ0_F0T_Motherboard_J_brd_V01_OCP.brd")
		(comment 1 "Grand Teton / footprints 2853-2855 of 6105")
	)
	(layers
		(0 "F.Cu" signal "TOP")
		(4 "In1.Cu" signal "GND")
		(6 "In2.Cu" signal "IN1")
		(8 "In3.Cu" signal "GND1")
		(10 "In4.Cu" signal "IN2")
		(12 "In5.Cu" signal "GND2")
		(14 "In6.Cu" signal "IN3")
		(16 "In7.Cu" signal "GND3")
		(18 "In8.Cu" signal "VCC")
		(20 "In9.Cu" signal "VCC1")
		(22 "In10.Cu" signal "GND4")
		(24 "In11.Cu" signal "IN4")
		(26 "In12.Cu" signal "GND5")
		(28 "In13.Cu" signal "IN5")
		(30 "In14.Cu" signal "GND6")
		(32 "In15.Cu" signal "IN6")
		(34 "In16.Cu" signal "GND7")
		(2 "B.Cu" signal "BOTTOM")
		(9 "F.Adhes" user "F.Adhesive")
		(11 "B.Adhes" user "B.Adhesive")
		(13 "F.Paste" user "Package Geometry/Pastemask Top")
		(15 "B.Paste" user "Package Geometry/Pastemask Bottom")
		(5 "F.SilkS" user "Ref Des/Silkscreen Top")
		(7 "B.SilkS" user "Ref Des/Silkscreen Bottom")
		(1 "F.Mask" user "Board Geometry/Soldermask Top")
		(3 "B.Mask" user "Board Geometry/Soldermask Bottom")
		(17 "Dwgs.User" user "User.Drawings")
		(19 "Cmts.User" user "User.Comments")
		(21 "Eco1.User" user "User.Eco1")
		(23 "Eco2.User" user "User.Eco2")
		(25 "Edge.Cuts" user "Board Geometry/Outline")
		(27 "Margin" user)
		(31 "F.CrtYd" user "Package Geometry/Place Bound Top")
		(29 "B.CrtYd" user "Package Geometry/Place Bound Bottom")
		(35 "F.Fab" user "Ref Des/Assembly Top")
		(33 "B.Fab" user "Ref Des/Assembly Bottom")
	)
	(footprint ""
		(layer "F.Cu")
		(at 456.927204 -70.255384 -90)
		(property "Reference" "PC2342"
			(at 0 0 270)
			(layer "F.SilkS")
			(hide yes)
			(effects
				(font
					(size 1.27 1.27)
				)
			)
		)
		(property "Value" ""
			(at 0 0 270)
			(layer "F.Fab")
			(effects
				(font
					(size 1.27 1.27)
				)
			)
		)
		(duplicate_pad_numbers_are_jumpers no)
		(fp_line
			(start -1.524 0.762)
			(end -1.524 -0.762)
			(stroke
				(width 0.1524)
				(type default)
			)
			(layer "F.SilkS")
		)
		(fp_line
			(start 1.524 0.762)
			(end -1.524 0.762)
			(stroke
				(width 0.1524)
				(type default)
			)
			(layer "F.SilkS")
		)
		(fp_line
			(start -1.524 -0.762)
			(end 1.524 -0.762)
			(stroke
				(width 0.1524)
				(type default)
			)
			(layer "F.SilkS")
		)
		(fp_line
			(start 1.524 -0.762)
			(end 1.524 0.762)
			(stroke
				(width 0.1524)
				(type default)
			)
			(layer "F.SilkS")
		)
		(fp_line
			(start -1.1049 0.724916)
			(end 1.1049 0.724916)
			(stroke
				(width 0.1)
				(type default)
			)
			(layer "F.Fab")
		)
		(fp_line
			(start 1.1049 0.724916)
			(end 1.1049 -0.724916)
			(stroke
				(width 0.1)
				(type default)
			)
			(layer "F.Fab")
		)
		(fp_line
			(start -1.1049 -0.724916)
			(end -1.1049 0.724916)
			(stroke
				(width 0.1)
				(type default)
			)
			(layer "F.Fab")
		)
		(fp_line
			(start 1.1049 -0.724916)
			(end -1.1049 -0.724916)
			(stroke
				(width 0.1)
				(type default)
			)
			(layer "F.Fab")
		)
		(pad "1" smd rect
			(at -0.889 0 90)
			(size 1.016 1.27)
			(layers "F.Cu" "F.Mask" "F.Paste")
			(net "SW_P3V3_AUX_FLT")
		)
		(pad "2" smd rect
			(at 0.889 0 90)
			(size 1.016 1.27)
			(layers "F.Cu" "F.Mask" "F.Paste")
			(net "GND")
		)
	)
	(footprint ""
		(layer "F.Cu")
		(at 382.168908 -75.376278 90)
		(property "Reference" "PC1235"
			(at 0 0 90)
			(layer "F.SilkS")
			(hide yes)
			(effects
				(font
					(size 1.27 1.27)
				)
			)
		)
		(property "Value" ""
			(at 0 0 90)
			(layer "F.Fab")
			(effects
				(font
					(size 1.27 1.27)
				)
			)
		)
		(duplicate_pad_numbers_are_jumpers no)
		(fp_line
			(start 0.7874 -0.4064)
			(end 0.7874 0.4064)
			(stroke
				(width 0.1524)
				(type default)
			)
			(layer "F.SilkS")
		)
		(fp_line
			(start -0.7874 -0.4064)
			(end 0.7874 -0.4064)
			(stroke
				(width 0.1524)
				(type default)
			)
			(layer "F.SilkS")
		)
		(fp_line
			(start 0.7874 0.4064)
			(end -0.7874 0.4064)
			(stroke
				(width 0.1524)
				(type default)
			)
			(layer "F.SilkS")
		)
		(fp_line
			(start -0.7874 0.4064)
			(end -0.7874 -0.4064)
			(stroke
				(width 0.1524)
				(type default)
			)
			(layer "F.SilkS")
		)
		(fp_line
			(start -0.12065 -0.305054)
			(end -0.12065 -0.2794)
			(stroke
				(width 0.1)
				(type default)
			)
			(layer "F.Fab")
		)
		(fp_line
			(start -0.67945 -0.305054)
			(end -0.12065 -0.305054)
			(stroke
				(width 0.1)
				(type default)
			)
			(layer "F.Fab")
		)
		(fp_line
			(start 0.67945 -0.3048)
			(end 0.67945 0.3048)
			(stroke
				(width 0.1)
				(type default)
			)
			(layer "F.Fab")
		)
		(fp_line
			(start 0.12065 -0.3048)
			(end 0.67945 -0.3048)
			(stroke
				(width 0.1)
				(type default)
			)
			(layer "F.Fab")
		)
		(fp_line
			(start 0.12065 -0.2794)
			(end 0.12065 -0.3048)
			(stroke
				(width 0.1)
				(type default)
			)
			(layer "F.Fab")
		)
		(fp_line
			(start -0.12065 -0.2794)
			(end 0.12065 -0.2794)
			(stroke
				(width 0.1)
				(type default)
			)
			(layer "F.Fab")
		)
		(fp_line
			(start 0.120396 0.2794)
			(end -0.12065 0.2794)
			(stroke
				(width 0.1)
				(type default)
			)
			(layer "F.Fab")
		)
		(fp_line
			(start -0.12065 0.2794)
			(end -0.12065 0.3048)
			(stroke
				(width 0.1)
				(type default)
			)
			(layer "F.Fab")
		)
		(fp_line
			(start 0.67945 0.3048)
			(end 0.120396 0.3048)
			(stroke
				(width 0.1)
				(type default)
			)
			(layer "F.Fab")
		)
		(fp_line
			(start 0.120396 0.3048)
			(end 0.120396 0.2794)
			(stroke
				(width 0.1)
				(type default)
			)
			(layer "F.Fab")
		)
		(fp_line
			(start -0.12065 0.3048)
			(end -0.67945 0.3048)
			(stroke
				(width 0.1)
				(type default)
			)
			(layer "F.Fab")
		)
		(fp_line
			(start -0.67945 0.3048)
			(end -0.67945 -0.305054)
			(stroke
				(width 0.1)
				(type default)
			)
			(layer "F.Fab")
		)
		(pad "1" smd circle
			(at -0.40005 0 90)
			(size 0 0)
			(layers "F.Cu" "F.Mask" "F.Paste")
			(net "SW_P1V8_PCH_AUX_BST")
		)
		(pad "2" smd circle
			(at 0.40005 0 90)
			(size 0 0)
			(layers "F.Cu" "F.Mask" "F.Paste")
			(net "SW_P1V8_PCH_AUX_SW")
		)
	)
	(footprint ""
		(layer "F.Cu")
		(at 194.346322 -79.057246)
		(property "Reference" "C640"
			(at 0 0 0)
			(layer "F.SilkS")
			(hide yes)
			(effects
				(font
					(size 1.27 1.27)
				)
			)
		)
		(property "Value" ""
			(at 0 0 0)
			(layer "F.Fab")
			(effects
				(font
					(size 1.27 1.27)
				)
			)
		)
		(duplicate_pad_numbers_are_jumpers no)
		(fp_line
			(start -0.7874 -0.4064)
			(end 0.7874 -0.4064)
			(stroke
				(width 0.1524)
				(type default)
			)
			(layer "F.SilkS")
		)
		(fp_line
			(start -0.7874 0.4064)
			(end -0.7874 -0.4064)
			(stroke
				(width 0.1524)
				(type default)
			)
			(layer "F.SilkS")
		)
		(fp_line
			(start 0.7874 -0.4064)
			(end 0.7874 0.4064)
			(stroke
				(width 0.1524)
				(type default)
			)
			(layer "F.SilkS")
		)
		(fp_line
			(start 0.7874 0.4064)
			(end -0.7874 0.4064)
			(stroke
				(width 0.1524)
				(type default)
			)
			(layer "F.SilkS")
		)
		(fp_line
			(start -0.67945 -0.305054)
			(end -0.12065 -0.305054)
			(stroke
				(width 0.1)
				(type default)
			)
			(layer "F.Fab")
		)
		(fp_line
			(start -0.67945 0.3048)
			(end -0.67945 -0.305054)
			(stroke
				(width 0.1)
				(type default)
			)
			(layer "F.Fab")
		)
		(fp_line
			(start -0.12065 -0.305054)
			(end -0.12065 -0.2794)
			(stroke
				(width 0.1)
				(type default)
			)
			(layer "F.Fab")
		)
		(fp_line
			(start -0.12065 -0.2794)
			(end 0.12065 -0.2794)
			(stroke
				(width 0.1)
				(type default)
			)
			(layer "F.Fab")
		)
		(fp_line
			(start -0.12065 0.2794)
			(end -0.12065 0.3048)
			(stroke
				(width 0.1)
				(type default)
			)
			(layer "F.Fab")
		)
		(fp_line
			(start -0.12065 0.3048)
			(end -0.67945 0.3048)
			(stroke
				(width 0.1)
				(type default)
			)
			(layer "F.Fab")
		)
		(fp_line
			(start 0.120396 0.2794)
			(end -0.12065 0.2794)
			(stroke
				(width 0.1)
				(type default)
			)
			(layer "F.Fab")
		)
		(fp_line
			(start 0.120396 0.3048)
			(end 0.120396 0.2794)
			(stroke
				(width 0.1)
				(type default)
			)
			(layer "F.Fab")
		)
		(fp_line
			(start 0.12065 -0.3048)
			(end 0.67945 -0.3048)
			(stroke
				(width 0.1)
				(type default)
			)
			(layer "F.Fab")
		)
		(fp_line
			(start 0.12065 -0.2794)
			(end 0.12065 -0.3048)
			(stroke
				(width 0.1)
				(type default)
			)
			(layer "F.Fab")
		)
		(fp_line
			(start 0.67945 -0.3048)
			(end 0.67945 0.3048)
			(stroke
				(width 0.1)
				(type default)
			)
			(layer "F.Fab")
		)
		(fp_line
			(start 0.67945 0.3048)
			(end 0.120396 0.3048)
			(stroke
				(width 0.1)
				(type default)
			)
			(layer "F.Fab")
		)
		(pad "1" smd circle
			(at -0.40005 0)
			(size 0 0)
			(layers "F.Cu" "F.Mask" "F.Paste")
			(net "P3V3_AUX")
		)
		(pad "2" smd circle
			(at 0.40005 0)
			(size 0 0)
			(layers "F.Cu" "F.Mask" "F.Paste")
			(net "GND")
		)
	)
)
